# T6G (Grand Teton) — schematic netlist excerpt (pin names and nets, part order shuffled) for the footprints in the layout excerpt that follows; sources: Cadence DE-HDL packaged netlist, KiCad conversion of 04192023_DAF0TMB3IC0_F0TG_MB_C_brd_V02_OCP.brd

C700  Q_CAP_DIFFBUS  DIFF BUS_0.22UF 6.3V 20% X6S  pkg C0201  page 67 : \1\ = P5E_CPU1_G1_TX_C_DN<4> ; \2\ = P5E_CPU1_G1_TX_DN<4>
R68  Q_RES  1K 1% EMPTY  pkg 0402LF  page 238 : A = P3V3_AUX ; B = CPU_FRU_ADDR0
C9050  Q_CAP  0.1UF 25V 10% X7R  pkg 0402  page 136 : A = P3V3_AUX ; B = GND

(kicad_pcb
	(version 20260206)
	(generator "pcbnew")
	(generator_version "10.0")
	(general
		(thickness 1.6)
		(legacy_teardrops no)
	)
	(paper "A4")
	(title_block
		(title "04192023_DAF0TMB3IC0_F0TG_MB_C_brd_V02_OCP.brd")
		(comment 1 "Grand Teton / footprints 1799-1801 of 8354")
	)
	(layers
		(0 "F.Cu" signal "TOP")
		(4 "In1.Cu" signal "GND")
		(6 "In2.Cu" signal "IN1")
		(8 "In3.Cu" signal "GND1")
		(10 "In4.Cu" signal "IN2")
		(12 "In5.Cu" signal "GND2")
		(14 "In6.Cu" signal "IN3")
		(16 "In7.Cu" signal "GND3")
		(18 "In8.Cu" signal "VCC")
		(20 "In9.Cu" signal "VCC1")
		(22 "In10.Cu" signal "GND4")
		(24 "In11.Cu" signal "IN4")
		(26 "In12.Cu" signal "GND5")
		(28 "In13.Cu" signal "IN5")
		(30 "In14.Cu" signal "GND6")
		(32 "In15.Cu" signal "IN6")
		(34 "In16.Cu" signal "GND7")
		(2 "B.Cu" signal "BOTTOM")
		(9 "F.Adhes" user "F.Adhesive")
		(11 "B.Adhes" user "B.Adhesive")
		(13 "F.Paste" user "Package Geometry/Pastemask Top")
		(15 "B.Paste" user "Package Geometry/Pastemask Bottom")
		(5 "F.SilkS" user "Ref Des/Silkscreen Top")
		(7 "B.SilkS" user "Ref Des/Silkscreen Bottom")
		(1 "F.Mask" user "Board Geometry/Soldermask Top")
		(3 "B.Mask" user "Board Geometry/Soldermask Bottom")
		(17 "Dwgs.User" user "User.Drawings")
		(19 "Cmts.User" user "User.Comments")
		(21 "Eco1.User" user "User.Eco1")
		(23 "Eco2.User" user "User.Eco2")
		(25 "Edge.Cuts" user "Board Geometry/Outline")
		(27 "Margin" user)
		(31 "F.CrtYd" user "Package Geometry/Place Bound Top")
		(29 "B.CrtYd" user "Package Geometry/Place Bound Bottom")
		(35 "F.Fab" user "Ref Des/Assembly Top")
		(33 "B.Fab" user "Ref Des/Assembly Bottom")
	)
	(footprint ""
		(layer "F.Cu")
		(at 46.548294 -17.623536 90)
		(property "Reference" "C700"
			(at 0 0 90)
			(layer "F.SilkS")
			(hide yes)
			(effects
				(font
					(size 1.27 1.27)
				)
			)
		)
		(property "Value" ""
			(at 0 0 90)
			(layer "F.Fab")
			(effects
				(font
					(size 1.27 1.27)
				)
			)
		)
		(duplicate_pad_numbers_are_jumpers no)
		(fp_line
			(start 0.299974 -0.150114)
			(end 0.299974 0.150114)
			(stroke
				(width 0.1)
				(type default)
			)
			(layer "F.Fab")
		)
		(fp_line
			(start -0.299974 -0.150114)
			(end 0.299974 -0.150114)
			(stroke
				(width 0.1)
				(type default)
			)
			(layer "F.Fab")
		)
		(fp_line
			(start 0.299974 0.150114)
			(end -0.299974 0.150114)
			(stroke
				(width 0.1)
				(type default)
			)
			(layer "F.Fab")
		)
		(fp_line
			(start -0.299974 0.150114)
			(end -0.299974 -0.150114)
			(stroke
				(width 0.1)
				(type default)
			)
			(layer "F.Fab")
		)
		(pad "1" smd rect
			(at -0.2667 0 90)
			(size 0.3048 0.381)
			(layers "F.Cu" "F.Mask" "F.Paste")
			(net "P5E_CPU1_G1_TX_C_DN<4>")
		)
		(pad "2" smd rect
			(at 0.2667 0 90)
			(size 0.3048 0.381)
			(layers "F.Cu" "F.Mask" "F.Paste")
			(net "P5E_CPU1_G1_TX_DN<4>")
		)
	)
	(footprint ""
		(layer "F.Cu")
		(at 216.9668 -101.92512 180)
		(property "Reference" "C9050"
			(at 0 0 180)
			(layer "F.SilkS")
			(hide yes)
			(effects
				(font
					(size 1.27 1.27)
				)
			)
		)
		(property "Value" ""
			(at 0 0 180)
			(layer "F.Fab")
			(effects
				(font
					(size 1.27 1.27)
				)
			)
		)
		(duplicate_pad_numbers_are_jumpers no)
		(fp_line
			(start 0.7874 0.4064)
			(end -0.7874 0.4064)
			(stroke
				(width 0.1524)
				(type default)
			)
			(layer "F.SilkS")
		)
		(fp_line
			(start 0.7874 -0.4064)
			(end 0.7874 0.4064)
			(stroke
				(width 0.1524)
				(type default)
			)
			(layer "F.SilkS")
		)
		(fp_line
			(start -0.7874 0.4064)
			(end -0.7874 -0.4064)
			(stroke
				(width 0.1524)
				(type default)
			)
			(layer "F.SilkS")
		)
		(fp_line
			(start -0.7874 -0.4064)
			(end 0.7874 -0.4064)
			(stroke
				(width 0.1524)
				(type default)
			)
			(layer "F.SilkS")
		)
		(fp_line
			(start 0.67945 0.3048)
			(end 0.120396 0.3048)
			(stroke
				(width 0.1)
				(type default)
			)
			(layer "F.Fab")
		)
		(fp_line
			(start 0.67945 -0.3048)
			(end 0.67945 0.3048)
			(stroke
				(width 0.1)
				(type default)
			)
			(layer "F.Fab")
		)
		(fp_line
			(start 0.12065 -0.2794)
			(end 0.12065 -0.3048)
			(stroke
				(width 0.1)
				(type default)
			)
			(layer "F.Fab")
		)
		(fp_line
			(start 0.12065 -0.3048)
			(end 0.67945 -0.3048)
			(stroke
				(width 0.1)
				(type default)
			)
			(layer "F.Fab")
		)
		(fp_line
			(start 0.120396 0.3048)
			(end 0.120396 0.2794)
			(stroke
				(width 0.1)
				(type default)
			)
			(layer "F.Fab")
		)
		(fp_line
			(start 0.120396 0.2794)
			(end -0.12065 0.2794)
			(stroke
				(width 0.1)
				(type default)
			)
			(layer "F.Fab")
		)
		(fp_line
			(start -0.12065 0.3048)
			(end -0.67945 0.3048)
			(stroke
				(width 0.1)
				(type default)
			)
			(layer "F.Fab")
		)
		(fp_line
			(start -0.12065 0.2794)
			(end -0.12065 0.3048)
			(stroke
				(width 0.1)
				(type default)
			)
			(layer "F.Fab")
		)
		(fp_line
			(start -0.12065 -0.2794)
			(end 0.12065 -0.2794)
			(stroke
				(width 0.1)
				(type default)
			)
			(layer "F.Fab")
		)
		(fp_line
			(start -0.12065 -0.305054)
			(end -0.12065 -0.2794)
			(stroke
				(width 0.1)
				(type default)
			)
			(layer "F.Fab")
		)
		(fp_line
			(start -0.67945 0.3048)
			(end -0.67945 -0.305054)
			(stroke
				(width 0.1)
				(type default)
			)
			(layer "F.Fab")
		)
		(fp_line
			(start -0.67945 -0.305054)
			(end -0.12065 -0.305054)
			(stroke
				(width 0.1)
				(type default)
			)
			(layer "F.Fab")
		)
		(pad "1" smd circle
			(at -0.40005 0 180)
			(size 0 0)
			(layers "F.Cu" "F.Mask" "F.Paste")
			(net "P3V3_AUX")
		)
		(pad "2" smd circle
			(at 0.40005 0 180)
			(size 0 0)
			(layers "F.Cu" "F.Mask" "F.Paste")
			(net "GND")
		)
	)
	(footprint ""
		(layer "F.Cu")
		(at 302.241458 -114.859308)
		(property "Reference" "R68"
			(at 0 0 0)
			(layer "F.SilkS")
			(hide yes)
			(effects
				(font
					(size 1.27 1.27)
				)
			)
		)
		(property "Value" ""
			(at 0 0 0)
			(layer "F.Fab")
			(effects
				(font
					(size 1.27 1.27)
				)
			)
		)
		(duplicate_pad_numbers_are_jumpers no)
		(fp_line
			(start -0.7874 -0.4064)
			(end 0.7874 -0.4064)
			(stroke
				(width 0.1524)
				(type default)
			)
			(layer "F.SilkS")
		)
		(fp_line
			(start -0.7874 0.4064)
			(end -0.7874 -0.4064)
			(stroke
				(width 0.1524)
				(type default)
			)
			(layer "F.SilkS")
		)
		(fp_line
			(start 0.7874 -0.4064)
			(end 0.7874 0.4064)
			(stroke
				(width 0.1524)
				(type default)
			)
			(layer "F.SilkS")
		)
		(fp_line
			(start 0.7874 0.4064)
			(end -0.7874 0.4064)
			(stroke
				(width 0.1524)
				(type default)
			)
			(layer "F.SilkS")
		)
		(fp_line
			(start -0.67945 -0.305054)
			(end -0.12065 -0.305054)
			(stroke
				(width 0.1)
				(type default)
			)
			(layer "F.Fab")
		)
		(fp_line
			(start -0.67945 0.3048)
			(end -0.67945 -0.305054)
			(stroke
				(width 0.1)
				(type default)
			)
			(layer "F.Fab")
		)
		(fp_line
			(start -0.12065 -0.305054)
			(end -0.12065 -0.2794)
			(stroke
				(width 0.1)
				(type default)
			)
			(layer "F.Fab")
		)
		(fp_line
			(start -0.12065 -0.2794)
			(end 0.12065 -0.2794)
			(stroke
				(width 0.1)
				(type default)
			)
			(layer "F.Fab")
		)
		(fp_line
			(start -0.12065 0.2794)
			(end -0.12065 0.3048)
			(stroke
				(width 0.1)
				(type default)
			)
			(layer "F.Fab")
		)
		(fp_line
			(start -0.12065 0.3048)
			(end -0.67945 0.3048)
			(stroke
				(width 0.1)
				(type default)
			)
			(layer "F.Fab")
		)
		(fp_line
			(start 0.120396 0.2794)
			(end -0.12065 0.2794)
			(stroke
				(width 0.1)
				(type default)
			)
			(layer "F.Fab")
		)
		(fp_line
			(start 0.120396 0.3048)
			(end 0.120396 0.2794)
			(stroke
				(width 0.1)
				(type default)
			)
			(layer "F.Fab")
		)
		(fp_line
			(start 0.12065 -0.3048)
			(end 0.67945 -0.3048)
			(stroke
				(width 0.1)
				(type default)
			)
			(layer "F.Fab")
		)
		(fp_line
			(start 0.12065 -0.2794)
			(end 0.12065 -0.3048)
			(stroke
				(width 0.1)
				(type default)
			)
			(layer "F.Fab")
		)
		(fp_line
			(start 0.67945 -0.3048)
			(end 0.67945 0.3048)
			(stroke
				(width 0.1)
				(type default)
			)
			(layer "F.Fab")
		)
		(fp_line
			(start 0.67945 0.3048)
			(end 0.120396 0.3048)
			(stroke
				(width 0.1)
				(type default)
			)
			(layer "F.Fab")
		)
		(pad "1" smd circle
			(at -0.40005 0)
			(size 0 0)
			(layers "F.Cu" "F.Mask" "F.Paste")
			(net "P3V3_AUX")
		)
		(pad "2" smd circle
			(at 0.40005 0)
			(size 0 0)
			(layers "F.Cu" "F.Mask" "F.Paste")
			(net "CPU_FRU_ADDR0")
		)
	)
)
